# S9S_MB_2U (Grand Teton) — schematic netlist excerpt (pin names and nets, part order shuffled) for the footprints in the layout excerpt that follows; sources: Cadence DE-HDL packaged netlist, KiCad conversion of 03242023_DA0F0TMBIJ0_F0T_Motherboard_J_brd_V01_OCP.brd

PC721_P0_2  Q_CAP  22UF 16V 20% X6S  pkg C0805  page 271 : A = SW_P12V_PVCCFA_EHV_FIVRA_CPU0_L ; B = GND
PC321  Q_CAPP  270UF 16V 20% OSCON  pkg THLF  page 267 : A = SW_P12V_PVCCIN_CPU0_FLT ; B = GND
PC250_P0_6  Q_CAP  2.2UF 10V 10% X6S  pkg C0402  page 269 : A = PVCCIN_CPU0_PVCC ; B = GND
C1524  Q_CAP_DIFFBUS  DIFF BUS_0.22UF 6.3V 20% X6S  pkg C0201  page 177 : \1\ = P5E_CPU1_PE3_TX_C_DN<11> ; \2\ = P5E_CPU1_PE3_TX_DN<11>

(kicad_pcb
	(version 20260206)
	(generator "pcbnew")
	(generator_version "10.0")
	(general
		(thickness 1.6)
		(legacy_teardrops no)
	)
	(paper "A4")
	(title_block
		(title "03242023_DA0F0TMBIJ0_F0T_Motherboard_J_brd_V01_OCP.brd")
		(comment 1 "Grand Teton / footprints 3252-3255 of 6105")
	)
	(layers
		(0 "F.Cu" signal "TOP")
		(4 "In1.Cu" signal "GND")
		(6 "In2.Cu" signal "IN1")
		(8 "In3.Cu" signal "GND1")
		(10 "In4.Cu" signal "IN2")
		(12 "In5.Cu" signal "GND2")
		(14 "In6.Cu" signal "IN3")
		(16 "In7.Cu" signal "GND3")
		(18 "In8.Cu" signal "VCC")
		(20 "In9.Cu" signal "VCC1")
		(22 "In10.Cu" signal "GND4")
		(24 "In11.Cu" signal "IN4")
		(26 "In12.Cu" signal "GND5")
		(28 "In13.Cu" signal "IN5")
		(30 "In14.Cu" signal "GND6")
		(32 "In15.Cu" signal "IN6")
		(34 "In16.Cu" signal "GND7")
		(2 "B.Cu" signal "BOTTOM")
		(9 "F.Adhes" user "F.Adhesive")
		(11 "B.Adhes" user "B.Adhesive")
		(13 "F.Paste" user "Package Geometry/Pastemask Top")
		(15 "B.Paste" user "Package Geometry/Pastemask Bottom")
		(5 "F.SilkS" user "Ref Des/Silkscreen Top")
		(7 "B.SilkS" user "Ref Des/Silkscreen Bottom")
		(1 "F.Mask" user "Board Geometry/Soldermask Top")
		(3 "B.Mask" user "Board Geometry/Soldermask Bottom")
		(17 "Dwgs.User" user "User.Drawings")
		(19 "Cmts.User" user "User.Comments")
		(21 "Eco1.User" user "User.Eco1")
		(23 "Eco2.User" user "User.Eco2")
		(25 "Edge.Cuts" user "Board Geometry/Outline")
		(27 "Margin" user)
		(31 "F.CrtYd" user "Package Geometry/Place Bound Top")
		(29 "B.CrtYd" user "Package Geometry/Place Bound Bottom")
		(35 "F.Fab" user "Ref Des/Assembly Top")
		(33 "B.Fab" user "Ref Des/Assembly Bottom")
	)
	(footprint ""
		(layer "F.Cu")
		(at 333.20228 -336.935572 -90)
		(property "Reference" "PC250_P0_6"
			(at 0 0 270)
			(layer "F.SilkS")
			(hide yes)
			(effects
				(font
					(size 1.27 1.27)
				)
			)
		)
		(property "Value" ""
			(at 0 0 270)
			(layer "F.Fab")
			(effects
				(font
					(size 1.27 1.27)
				)
			)
		)
		(duplicate_pad_numbers_are_jumpers no)
		(fp_line
			(start -0.7874 0.4064)
			(end -0.7874 -0.4064)
			(stroke
				(width 0.1524)
				(type default)
			)
			(layer "F.SilkS")
		)
		(fp_line
			(start 0.7874 0.4064)
			(end -0.7874 0.4064)
			(stroke
				(width 0.1524)
				(type default)
			)
			(layer "F.SilkS")
		)
		(fp_line
			(start -0.7874 -0.4064)
			(end 0.7874 -0.4064)
			(stroke
				(width 0.1524)
				(type default)
			)
			(layer "F.SilkS")
		)
		(fp_line
			(start 0.7874 -0.4064)
			(end 0.7874 0.4064)
			(stroke
				(width 0.1524)
				(type default)
			)
			(layer "F.SilkS")
		)
		(fp_line
			(start -0.67945 0.3048)
			(end -0.67945 -0.305054)
			(stroke
				(width 0.1)
				(type default)
			)
			(layer "F.Fab")
		)
		(fp_line
			(start -0.12065 0.3048)
			(end -0.67945 0.3048)
			(stroke
				(width 0.1)
				(type default)
			)
			(layer "F.Fab")
		)
		(fp_line
			(start 0.120396 0.3048)
			(end 0.120396 0.2794)
			(stroke
				(width 0.1)
				(type default)
			)
			(layer "F.Fab")
		)
		(fp_line
			(start 0.67945 0.3048)
			(end 0.120396 0.3048)
			(stroke
				(width 0.1)
				(type default)
			)
			(layer "F.Fab")
		)
		(fp_line
			(start -0.12065 0.2794)
			(end -0.12065 0.3048)
			(stroke
				(width 0.1)
				(type default)
			)
			(layer "F.Fab")
		)
		(fp_line
			(start 0.120396 0.2794)
			(end -0.12065 0.2794)
			(stroke
				(width 0.1)
				(type default)
			)
			(layer "F.Fab")
		)
		(fp_line
			(start -0.12065 -0.2794)
			(end 0.12065 -0.2794)
			(stroke
				(width 0.1)
				(type default)
			)
			(layer "F.Fab")
		)
		(fp_line
			(start 0.12065 -0.2794)
			(end 0.12065 -0.3048)
			(stroke
				(width 0.1)
				(type default)
			)
			(layer "F.Fab")
		)
		(fp_line
			(start 0.12065 -0.3048)
			(end 0.67945 -0.3048)
			(stroke
				(width 0.1)
				(type default)
			)
			(layer "F.Fab")
		)
		(fp_line
			(start 0.67945 -0.3048)
			(end 0.67945 0.3048)
			(stroke
				(width 0.1)
				(type default)
			)
			(layer "F.Fab")
		)
		(fp_line
			(start -0.67945 -0.305054)
			(end -0.12065 -0.305054)
			(stroke
				(width 0.1)
				(type default)
			)
			(layer "F.Fab")
		)
		(fp_line
			(start -0.12065 -0.305054)
			(end -0.12065 -0.2794)
			(stroke
				(width 0.1)
				(type default)
			)
			(layer "F.Fab")
		)
		(pad "1" smd circle
			(at -0.40005 0 270)
			(size 0 0)
			(layers "F.Cu" "F.Mask" "F.Paste")
			(net "PVCCIN_CPU0_PVCC")
		)
		(pad "2" smd circle
			(at 0.40005 0 270)
			(size 0 0)
			(layers "F.Cu" "F.Mask" "F.Paste")
			(net "GND")
		)
	)
	(footprint ""
		(layer "F.Cu")
		(at 133.728714 -408.517344 -90)
		(property "Reference" "C1524"
			(at 0 0 270)
			(layer "F.SilkS")
			(hide yes)
			(effects
				(font
					(size 1.27 1.27)
				)
			)
		)
		(property "Value" ""
			(at 0 0 270)
			(layer "F.Fab")
			(effects
				(font
					(size 1.27 1.27)
				)
			)
		)
		(duplicate_pad_numbers_are_jumpers no)
		(fp_line
			(start -0.299974 0.150114)
			(end -0.299974 -0.150114)
			(stroke
				(width 0.1)
				(type default)
			)
			(layer "F.Fab")
		)
		(fp_line
			(start 0.299974 0.150114)
			(end -0.299974 0.150114)
			(stroke
				(width 0.1)
				(type default)
			)
			(layer "F.Fab")
		)
		(fp_line
			(start -0.299974 -0.150114)
			(end 0.299974 -0.150114)
			(stroke
				(width 0.1)
				(type default)
			)
			(layer "F.Fab")
		)
		(fp_line
			(start 0.299974 -0.150114)
			(end 0.299974 0.150114)
			(stroke
				(width 0.1)
				(type default)
			)
			(layer "F.Fab")
		)
		(pad "1" smd rect
			(at -0.2667 0 270)
			(size 0.3048 0.381)
			(layers "F.Cu" "F.Mask" "F.Paste")
			(net "P5E_CPU1_PE3_TX_C_DN<11>")
		)
		(pad "2" smd rect
			(at 0.2667 0 270)
			(size 0.3048 0.381)
			(layers "F.Cu" "F.Mask" "F.Paste")
			(net "P5E_CPU1_PE3_TX_DN<11>")
		)
	)
	(footprint ""
		(layer "F.Cu")
		(at 368.105182 -343.902284 90)
		(property "Reference" "PC321"
			(at 0 0 90)
			(layer "F.SilkS")
			(hide yes)
			(effects
				(font
					(size 1.27 1.27)
				)
			)
		)
		(property "Value" ""
			(at 0 0 90)
			(layer "F.Fab")
			(effects
				(font
					(size 1.27 1.27)
				)
			)
		)
		(duplicate_pad_numbers_are_jumpers no)
		(fp_line
			(start -3.400044 1.249934)
			(end 3.400044 1.249934)
			(stroke
				(width 0.1524)
				(type default)
			)
			(layer "F.SilkS")
		)
		(fp_circle
			(center 0 1.249934)
			(end 0 4.649978)
			(stroke
				(width 0.1524)
				(type default)
			)
			(fill no)
			(layer "F.SilkS")
		)
		(fp_poly
			(pts
				(arc
					(start -3.400044 1.249934)
					(mid 0 4.649978)
					(end 3.400044 1.249934)
				)
			)
			(stroke
				(width 0)
				(type default)
			)
			(fill yes)
			(layer "F.SilkS")
		)
		(fp_circle
			(center 0 1.249934)
			(end 0 4.649978)
			(stroke
				(width 0.1)
				(type default)
			)
			(fill no)
			(layer "F.Fab")
		)
		(pad "1" thru_hole rect
			(at 0 0 90)
			(size 1.524 1.524)
			(drill 1.016)
			(layers "*.Cu" "*.Mask")
			(remove_unused_layers no)
			(net "SW_P12V_PVCCIN_CPU0_FLT")
			(clearance 0)
			(padstack
				(mode front_inner_back)
				(layer "Inner"
					(shape circle)
					(size 1.524 1.524)
					(clearance 0)
				)
				(layer "B.Cu"
					(shape rect)
					(size 1.524 1.524)
					(clearance 0)
				)
			)
		)
		(pad "2" thru_hole circle
			(at 0 2.500122 90)
			(size 1.524 1.524)
			(drill 1.016)
			(layers "*.Cu" "*.Mask")
			(remove_unused_layers no)
			(net "GND")
			(clearance 0)
		)
	)
	(footprint ""
		(layer "F.Cu")
		(at 303.553368 -367.337848)
		(property "Reference" "PC721_P0_2"
			(at 0 0 0)
			(layer "F.SilkS")
			(hide yes)
			(effects
				(font
					(size 1.27 1.27)
				)
			)
		)
		(property "Value" ""
			(at 0 0 0)
			(layer "F.Fab")
			(effects
				(font
					(size 1.27 1.27)
				)
			)
		)
		(duplicate_pad_numbers_are_jumpers no)
		(fp_line
			(start -1.524 -0.762)
			(end 1.524 -0.762)
			(stroke
				(width 0.1524)
				(type default)
			)
			(layer "F.SilkS")
		)
		(fp_line
			(start -1.524 0.762)
			(end -1.524 -0.762)
			(stroke
				(width 0.1524)
				(type default)
			)
			(layer "F.SilkS")
		)
		(fp_line
			(start 1.524 -0.762)
			(end 1.524 0.762)
			(stroke
				(width 0.1524)
				(type default)
			)
			(layer "F.SilkS")
		)
		(fp_line
			(start 1.524 0.762)
			(end -1.524 0.762)
			(stroke
				(width 0.1524)
				(type default)
			)
			(layer "F.SilkS")
		)
		(fp_line
			(start -1.1049 -0.724916)
			(end -1.1049 0.724916)
			(stroke
				(width 0.1)
				(type default)
			)
			(layer "F.Fab")
		)
		(fp_line
			(start -1.1049 0.724916)
			(end 1.1049 0.724916)
			(stroke
				(width 0.1)
				(type default)
			)
			(layer "F.Fab")
		)
		(fp_line
			(start 1.1049 -0.724916)
			(end -1.1049 -0.724916)
			(stroke
				(width 0.1)
				(type default)
			)
			(layer "F.Fab")
		)
		(fp_line
			(start 1.1049 0.724916)
			(end 1.1049 -0.724916)
			(stroke
				(width 0.1)
				(type default)
			)
			(layer "F.Fab")
		)
		(pad "1" smd rect
			(at -0.889 0 180)
			(size 1.016 1.27)
			(layers "F.Cu" "F.Mask" "F.Paste")
			(net "SW_P12V_PVCCFA_EHV_FIVRA_CPU0_L")
		)
		(pad "2" smd rect
			(at 0.889 0 180)
			(size 1.016 1.27)
			(layers "F.Cu" "F.Mask" "F.Paste")
			(net "GND")
		)
	)
)
